# BASEBOARD_FAB2 (Tioga Pass) — schematic netlist excerpt (pin names and nets, part order shuffled) for the footprints in the layout excerpt that follows; sources: Cadence DE-HDL packaged netlist, KiCad conversion of Wiwynn_Tioga_Pass_MB.brd

J6U1  SCONN288_H44441003  SCONN  pkg PIP  page 46
  \12v\(1)  = P12V_NVDIMM_ABC
  VSS(93)  = GND
  DQ(4)  = M_B_DQ<4>
  VSS(92)  = GND
  DQ(0)  = M_B_DQ<0>
  VSS(91)  = GND
  DQS9P  = M_B_DQS_DP<9>
  DQS9N  = M_B_DQS_DN<9>
  VSS(90)  = GND
  DQ(6)  = M_B_DQ<6>
  VSS(89)  = GND
  DQ(2)  = M_B_DQ<2>
  VSS(88)  = GND
  DQ(12)  = M_B_DQ<12>
  VSS(87)  = GND
  DQ(8)  = M_B_DQ<8>
  VSS(86)  = GND
  DQS10P  = M_B_DQS_DP<10>
  DQS10N  = M_B_DQS_DN<10>
  VSS(85)  = GND
  DQ(14)  = M_B_DQ<14>
  VSS(84)  = GND
  DQ(10)  = M_B_DQ<10>
  VSS(83)  = GND
  DQ(20)  = M_B_DQ<20>
  VSS(82)  = GND
  DQ(16)  = M_B_DQ<16>
  VSS(81)  = GND
  DQS11P  = M_B_DQS_DP<11>
  DQS11N  = M_B_DQS_DN<11>
  VSS(80)  = GND
  DQ(22)  = M_B_DQ<22>
  VSS(79)  = GND
  DQ(18)  = M_B_DQ<18>
  VSS(78)  = GND
  DQ(28)  = M_B_DQ<28>
  VSS(77)  = GND
  DQ(24)  = M_B_DQ<24>
  VSS(76)  = GND
  DQS12P  = M_B_DQS_DP<12>
  DQS12N  = M_B_DQS_DN<12>
  VSS(75)  = GND
  DQ(30)  = M_B_DQ<30>
  VSS(74)  = GND
  DQ(26)  = M_B_DQ<26>
  VSS(73)  = GND
  CB(4)  = M_B_ECC<4>
  VSS(72)  = GND
  CB(0)  = M_B_ECC<0>
  VSS(71)  = GND
  DQS17P  = M_B_DQS_DP<17>
  DQS17N  = M_B_DQS_DN<17>
  VSS(70)  = GND
  CB(6)  = M_B_ECC<6>
  VSS(69)  = GND
  CB(2)  = M_B_ECC<2>
  VSS(68)  = GND
  RESET_N  = M_ABC_RST_N
  VDD(25)  = PVDDQ_ABC
  CKE(0)  = M_B_CKE<2>
  VDD(24)  = PVDDQ_ABC
  ACT_N  = M_B_ACT_N
  BG(0)  = M_B_BG<0>
  VDD(23)  = PVDDQ_ABC
  A12  = M_B_MA<12>
  A9  = M_B_MA<9>
  VDD(22)  = PVDDQ_ABC
  A8  = M_B_MA<8>
  A6  = M_B_MA<6>
  VDD(21)  = PVDDQ_ABC
  A3  = M_B_MA<3>
  A1  = M_B_MA<1>
  VDD(20)  = PVDDQ_ABC
  CK0P  = M_B_CLK_DP<2>
  CK0N  = M_B_CLK_DN<2>
  VDD(19)  = PVDDQ_ABC
  VTT(1)  = PVTT_ABC
  EVENT_N  = FM_DIMM_EVENT_COD_N
  A0  = M_B_MA<0>
  VDD(18)  = PVDDQ_ABC
  BA(0)  = M_B_BA<0>
  A16_RAS_N  = M_B_MA<16>
  VDD(17)  = PVDDQ_ABC
  S0_N  = M_B_CS_N<4>
  VDD(16)  = PVDDQ_ABC
  A15_CAS_N  = M_B_MA<15>
  ODT(0)  = M_B_ODT<2>
  VDD(15)  = PVDDQ_ABC
  S1_N  = M_B_CS_N<5>
  VDD(14)  = PVDDQ_ABC
  ODT(1)  = M_B_ODT<3>
  VDD(13)  = PVDDQ_ABC
  S2_N_C(0)  = M_B_CS_N<6>
  VSS(67)  = GND
  DQ(36)  = M_B_DQ<36>
  VSS(66)  = GND
  DQ(32)  = M_B_DQ<32>
  VSS(65)  = GND
  DQS13P  = M_B_DQS_DP<13>
  DQS13N  = M_B_DQS_DN<13>
  VSS(64)  = GND
  DQ(38)  = M_B_DQ<38>
  VSS(63)  = GND
  DQ(34)  = M_B_DQ<34>
  VSS(62)  = GND
  DQ(44)  = M_B_DQ<44>
  VSS(61)  = GND
  DQ(40)  = M_B_DQ<40>
  VSS(60)  = GND
  DQS14P  = M_B_DQS_DP<14>
  DQS14N  = M_B_DQS_DN<14>
  VSS(59)  = GND
  DQ(46)  = M_B_DQ<46>
  VSS(58)  = GND
  DQ(42)  = M_B_DQ<42>
  VSS(57)  = GND
  DQ(52)  = M_B_DQ<52>
  VSS(56)  = GND
  DQ(48)  = M_B_DQ<48>
  VSS(55)  = GND
  DQS15P  = M_B_DQS_DP<15>
  DQS15N  = M_B_DQS_DN<15>
  VSS(54)  = GND
  DQ(54)  = M_B_DQ<54>
  VSS(53)  = GND
  DQ(50)  = M_B_DQ<50>
  VSS(52)  = GND
  DQ(60)  = M_B_DQ<60>
  VSS(51)  = GND
  DQ(56)  = M_B_DQ<56>
  VSS(50)  = GND
  DQS16P  = M_B_DQS_DP<16>
  DQS16N  = M_B_DQS_DN<16>
  VSS(49)  = GND
  DQ(62)  = M_B_DQ<62>
  VSS(48)  = GND
  DQ(58)  = M_B_DQ<58>
  VSS(47)  = GND
  SA(0)  = PVPP_ABC
  SA(1)  = PVPP_ABC
  SCL  = SMB_DDR_ABC_VPP_SCL
  VPP(4)  = PVPP_ABC
  VPP(3)  = PVPP_ABC
  RFU(2)  = TP_CH_B_DIMM_B1_RFU_2
  \12v\(0)  = P12V_NVDIMM_ABC
  VREFCA  = M_B_VREF
  VSS(46)  = GND
  DQ(5)  = M_B_DQ<5>
  VSS(45)  = GND
  DQ(1)  = M_B_DQ<1>
  VSS(44)  = GND
  DQS0N  = M_B_DQS_DN<0>
  DQS0P  = M_B_DQS_DP<0>
  VSS(43)  = GND
  DQ(7)  = M_B_DQ<7>
  VSS(42)  = GND
  DQ(3)  = M_B_DQ<3>
  VSS(41)  = GND
  DQ(13)  = M_B_DQ<13>
  VSS(40)  = GND
  DQ(9)  = M_B_DQ<9>
  VSS(39)  = GND
  DQS1N  = M_B_DQS_DN<1>
  DQS1P  = M_B_DQS_DP<1>
  VSS(38)  = GND
  DQ(15)  = M_B_DQ<15>
  VSS(37)  = GND
  DQ(11)  = M_B_DQ<11>
  VSS(36)  = GND
  DQ(21)  = M_B_DQ<21>
  VSS(35)  = GND
  DQ(17)  = M_B_DQ<17>
  VSS(34)  = GND
  DQS2N  = M_B_DQS_DN<2>
  DQS2P  = M_B_DQS_DP<2>
  VSS(33)  = GND
  DQ(23)  = M_B_DQ<23>
  VSS(32)  = GND
  DQ(19)  = M_B_DQ<19>
  VSS(31)  = GND
  DQ(29)  = M_B_DQ<29>
  VSS(30)  = GND
  DQ(25)  = M_B_DQ<25>
  VSS(29)  = GND
  DQS3N  = M_B_DQS_DN<3>
  DQS3P  = M_B_DQS_DP<3>
  VSS(28)  = GND
  DQ(31)  = M_B_DQ<31>
  VSS(27)  = GND
  DQ(27)  = M_B_DQ<27>
  VSS(26)  = GND
  CB(5)  = M_B_ECC<5>
  VSS(25)  = GND
  CB(1)  = M_B_ECC<1>
  VSS(24)  = GND
  DQS8N  = M_B_DQS_DN<8>
  DQS8P  = M_B_DQS_DP<8>
  VSS(23)  = GND
  CB(7)  = M_B_ECC<7>
  VSS(22)  = GND
  CB(3)  = M_B_ECC<3>
  VSS(21)  = GND
  CKE(1)  = M_B_CKE<3>
  VDD(12)  = PVDDQ_ABC
  RFU(0)  = TP_CH_B_DIMM_B1_RFU_0
  VDD(11)  = PVDDQ_ABC
  BG(1)  = M_B_BG<1>
  ALERT_N  = M_B_ALERT_N
  VDD(10)  = PVDDQ_ABC
  A11  = M_B_MA<11>
  A7  = M_B_MA<7>
  VDD(9)  = PVDDQ_ABC
  A5  = M_B_MA<5>
  A4  = M_B_MA<4>
  VDD(8)  = PVDDQ_ABC
  A2  = M_B_MA<2>
  VDD(7)  = PVDDQ_ABC
  CK1P  = M_B_CLK_DP<3>
  CK1N  = M_B_CLK_DN<3>
  VDD(6)  = PVDDQ_ABC
  VTT(0)  = PVTT_ABC
  PAR  = M_B_PAR
  VDD(5)  = PVDDQ_ABC
  BA(1)  = M_B_BA<1>
  A10  = M_B_MA<10>
  VDD(4)  = PVDDQ_ABC
  RFU(1)  = TP_CH_B_DIMM_B1_RFU_1
  A14_WE_N  = M_B_MA<14>
  VDD(3)  = PVDDQ_ABC
  SAVE_N_NC  = FM_ADR_COMPLETE_ABC_N
  VDD(2)  = PVDDQ_ABC
  A13  = M_B_MA<13>
  VDD(1)  = PVDDQ_ABC
  A17  = M_B_MA<17>
  C(2)  = M_B_C<2>
  VDD(0)  = PVDDQ_ABC
  S3_N_C(1)  = M_B_CS_N<7>
  SA(2)  = GND
  VSS(20)  = GND
  DQ(37)  = M_B_DQ<37>
  VSS(19)  = GND
  DQ(33)  = M_B_DQ<33>
  VSS(18)  = GND
  DQS4N  = M_B_DQS_DN<4>
  DQS4P  = M_B_DQS_DP<4>
  VSS(17)  = GND
  DQ(39)  = M_B_DQ<39>
  VSS(16)  = GND
  DQ(35)  = M_B_DQ<35>
  VSS(15)  = GND
  DQ(45)  = M_B_DQ<45>
  VSS(14)  = GND
  DQ(41)  = M_B_DQ<41>
  VSS(13)  = GND
  DQS5N  = M_B_DQS_DN<5>
  DQS5P  = M_B_DQS_DP<5>
  VSS(12)  = GND
  DQ(47)  = M_B_DQ<47>
  VSS(11)  = GND
  DQ(43)  = M_B_DQ<43>
  VSS(10)  = GND
  DQ(53)  = M_B_DQ<53>
  VSS(9)  = GND
  DQ(49)  = M_B_DQ<49>
  VSS(8)  = GND
  DQS6N  = M_B_DQS_DN<6>
  DQS6P  = M_B_DQS_DP<6>
  VSS(7)  = GND
  DQ(55)  = M_B_DQ<55>
  VSS(6)  = GND
  DQ(51)  = M_B_DQ<51>
  VSS(5)  = GND
  DQ(61)  = M_B_DQ<61>
  VSS(4)  = GND
  DQ(57)  = M_B_DQ<57>
  VSS(3)  = GND
  DQS7N  = M_B_DQS_DN<7>
  DQS7P  = M_B_DQS_DP<7>
  VSS(2)  = GND
  DQ(63)  = M_B_DQ<63>
  VSS(1)  = GND
  DQ(59)  = M_B_DQ<59>
  VSS(0)  = GND
  VDDSPD  = PVPP_ABC
  SDA  = SMB_DDR_ABC_VPP_SDA
  VPP(1)  = PVPP_ABC
  VPP(0)  = PVPP_ABC
  VPP(2)  = PVPP_ABC

(kicad_pcb
	(version 20260206)
	(generator "pcbnew")
	(generator_version "10.0")
	(general
		(thickness 1.6)
		(legacy_teardrops no)
	)
	(paper "A4")
	(title_block
		(title "Wiwynn_Tioga_Pass_MB.brd")
		(comment 1 "Tioga Pass / footprint 2988 of 4770 (J6U1), pads 101-151 of 291")
	)
	(layers
		(0 "F.Cu" signal "TOP")
		(4 "In1.Cu" signal "L2GND")
		(6 "In2.Cu" signal "L3")
		(8 "In3.Cu" signal "L4GND")
		(10 "In4.Cu" signal "L5")
		(12 "In5.Cu" signal "L6GND")
		(14 "In6.Cu" signal "L7VCC")
		(16 "In7.Cu" signal "L8VCC")
		(18 "In8.Cu" signal "L9GND")
		(20 "In9.Cu" signal "L10")
		(22 "In10.Cu" signal "L11GND")
		(24 "In11.Cu" signal "L12")
		(26 "In12.Cu" signal "L13GND")
		(2 "B.Cu" signal "BOTTOM")
		(9 "F.Adhes" user "F.Adhesive")
		(11 "B.Adhes" user "B.Adhesive")
		(13 "F.Paste" user "Package Geometry/Pastemask Top")
		(15 "B.Paste" user "Package Geometry/Pastemask Bottom")
		(5 "F.SilkS" user "Ref Des/Silkscreen Top")
		(7 "B.SilkS" user "Ref Des/Silkscreen Bottom")
		(1 "F.Mask" user "Board Geometry/Soldermask Top")
		(3 "B.Mask" user "Board Geometry/Soldermask Bottom")
		(17 "Dwgs.User" user "User.Drawings")
		(19 "Cmts.User" user "User.Comments")
		(21 "Eco1.User" user "User.Eco1")
		(23 "Eco2.User" user "User.Eco2")
		(25 "Edge.Cuts" user "Board Geometry/Outline")
		(27 "Margin" user)
		(31 "F.CrtYd" user "Package Geometry/Place Bound Top")
		(29 "B.CrtYd" user "Package Geometry/Place Bound Bottom")
		(35 "F.Fab" user "Ref Des/Assembly Top")
		(33 "B.Fab" user "Ref Des/Assembly Bottom")
	)
	(footprint ""
		(layer "B.Cu")
		(at 194.700398 -15.222982 90)
		(property "Reference" "J6U1"
			(at 2.530348 39.10711 0)
			(unlocked yes)
			(layer "B.SilkS")
			(effects
				(font
					(size 0.7874 0.5842)
					(thickness 0.1524)
				)
				(justify left mirror)
			)
		)
		(property "Value" ""
			(at 0 0 90)
			(layer "B.Fab")
			(effects
				(font
					(size 1.27 1.27)
				)
				(justify mirror)
			)
		)
		(duplicate_pad_numbers_are_jumpers no)
		(pad "98" smd rect
			(at 0 87.54999 270)
			(size 1.8034 0.508)
			(layers "B.Cu" "B.Mask" "B.Paste")
			(net "GND")
		)
		(pad "99" smd rect
			(at 0 88.399874 270)
			(size 1.8034 0.508)
			(layers "B.Cu" "B.Mask" "B.Paste")
			(net "M_B_DQS_DP<13>")
		)
		(pad "100" smd rect
			(at 0 89.250012 270)
			(size 1.8034 0.508)
			(layers "B.Cu" "B.Mask" "B.Paste")
			(net "M_B_DQS_DN<13>")
		)
		(pad "101" smd rect
			(at 0 90.099896 270)
			(size 1.8034 0.508)
			(layers "B.Cu" "B.Mask" "B.Paste")
			(net "GND")
		)
		(pad "102" smd rect
			(at 0 90.950034 270)
			(size 1.8034 0.508)
			(layers "B.Cu" "B.Mask" "B.Paste")
			(net "M_B_DQ<38>")
		)
		(pad "103" smd rect
			(at 0 91.799918 270)
			(size 1.8034 0.508)
			(layers "B.Cu" "B.Mask" "B.Paste")
			(net "GND")
		)
		(pad "104" smd rect
			(at 0 92.650056 270)
			(size 1.8034 0.508)
			(layers "B.Cu" "B.Mask" "B.Paste")
			(net "M_B_DQ<34>")
		)
		(pad "105" smd rect
			(at 0 93.49994 270)
			(size 1.8034 0.508)
			(layers "B.Cu" "B.Mask" "B.Paste")
			(net "GND")
		)
		(pad "106" smd rect
			(at 0 94.350078 270)
			(size 1.8034 0.508)
			(layers "B.Cu" "B.Mask" "B.Paste")
			(net "M_B_DQ<44>")
		)
		(pad "107" smd rect
			(at 0 95.199962 270)
			(size 1.8034 0.508)
			(layers "B.Cu" "B.Mask" "B.Paste")
			(net "GND")
		)
		(pad "108" smd rect
			(at 0 96.0501 270)
			(size 1.8034 0.508)
			(layers "B.Cu" "B.Mask" "B.Paste")
			(net "M_B_DQ<40>")
		)
		(pad "109" smd rect
			(at 0 96.899984 270)
			(size 1.8034 0.508)
			(layers "B.Cu" "B.Mask" "B.Paste")
			(net "GND")
		)
		(pad "110" smd rect
			(at 0 97.750122 270)
			(size 1.8034 0.508)
			(layers "B.Cu" "B.Mask" "B.Paste")
			(net "M_B_DQS_DP<14>")
		)
		(pad "111" smd rect
			(at 0 98.600006 270)
			(size 1.8034 0.508)
			(layers "B.Cu" "B.Mask" "B.Paste")
			(net "M_B_DQS_DN<14>")
		)
		(pad "112" smd rect
			(at 0 99.44989 270)
			(size 1.8034 0.508)
			(layers "B.Cu" "B.Mask" "B.Paste")
			(net "GND")
		)
		(pad "113" smd rect
			(at 0 100.300028 270)
			(size 1.8034 0.508)
			(layers "B.Cu" "B.Mask" "B.Paste")
			(net "M_B_DQ<46>")
		)
		(pad "114" smd rect
			(at 0 101.149912 270)
			(size 1.8034 0.508)
			(layers "B.Cu" "B.Mask" "B.Paste")
			(net "GND")
		)
		(pad "115" smd rect
			(at 0 102.00005 270)
			(size 1.8034 0.508)
			(layers "B.Cu" "B.Mask" "B.Paste")
			(net "M_B_DQ<42>")
		)
		(pad "116" smd rect
			(at 0 102.849934 270)
			(size 1.8034 0.508)
			(layers "B.Cu" "B.Mask" "B.Paste")
			(net "GND")
		)
		(pad "117" smd rect
			(at 0 103.700072 270)
			(size 1.8034 0.508)
			(layers "B.Cu" "B.Mask" "B.Paste")
			(net "M_B_DQ<52>")
		)
		(pad "118" smd rect
			(at 0 104.549956 270)
			(size 1.8034 0.508)
			(layers "B.Cu" "B.Mask" "B.Paste")
			(net "GND")
		)
		(pad "119" smd rect
			(at 0 105.400094 270)
			(size 1.8034 0.508)
			(layers "B.Cu" "B.Mask" "B.Paste")
			(net "M_B_DQ<48>")
		)
		(pad "120" smd rect
			(at 0 106.249978 270)
			(size 1.8034 0.508)
			(layers "B.Cu" "B.Mask" "B.Paste")
			(net "GND")
		)
		(pad "121" smd rect
			(at 0 107.100116 270)
			(size 1.8034 0.508)
			(layers "B.Cu" "B.Mask" "B.Paste")
			(net "M_B_DQS_DP<15>")
		)
		(pad "122" smd rect
			(at 0 107.95 270)
			(size 1.8034 0.508)
			(layers "B.Cu" "B.Mask" "B.Paste")
			(net "M_B_DQS_DN<15>")
		)
		(pad "123" smd rect
			(at 0 108.799884 270)
			(size 1.8034 0.508)
			(layers "B.Cu" "B.Mask" "B.Paste")
			(net "GND")
		)
		(pad "124" smd rect
			(at 0 109.650022 270)
			(size 1.8034 0.508)
			(layers "B.Cu" "B.Mask" "B.Paste")
			(net "M_B_DQ<54>")
		)
		(pad "125" smd rect
			(at 0 110.499906 270)
			(size 1.8034 0.508)
			(layers "B.Cu" "B.Mask" "B.Paste")
			(net "GND")
		)
		(pad "126" smd rect
			(at 0 111.350044 270)
			(size 1.8034 0.508)
			(layers "B.Cu" "B.Mask" "B.Paste")
			(net "M_B_DQ<50>")
		)
		(pad "127" smd rect
			(at 0 112.199928 270)
			(size 1.8034 0.508)
			(layers "B.Cu" "B.Mask" "B.Paste")
			(net "GND")
		)
		(pad "128" smd rect
			(at 0 113.050066 270)
			(size 1.8034 0.508)
			(layers "B.Cu" "B.Mask" "B.Paste")
			(net "M_B_DQ<60>")
		)
		(pad "129" smd rect
			(at 0 113.89995 270)
			(size 1.8034 0.508)
			(layers "B.Cu" "B.Mask" "B.Paste")
			(net "GND")
		)
		(pad "130" smd rect
			(at 0 114.750088 270)
			(size 1.8034 0.508)
			(layers "B.Cu" "B.Mask" "B.Paste")
			(net "M_B_DQ<56>")
		)
		(pad "131" smd rect
			(at 0 115.599972 270)
			(size 1.8034 0.508)
			(layers "B.Cu" "B.Mask" "B.Paste")
			(net "GND")
		)
		(pad "132" smd rect
			(at 0 116.45011 270)
			(size 1.8034 0.508)
			(layers "B.Cu" "B.Mask" "B.Paste")
			(net "M_B_DQS_DP<16>")
		)
		(pad "133" smd rect
			(at 0 117.299994 270)
			(size 1.8034 0.508)
			(layers "B.Cu" "B.Mask" "B.Paste")
			(net "M_B_DQS_DN<16>")
		)
		(pad "134" smd rect
			(at 0 118.149878 270)
			(size 1.8034 0.508)
			(layers "B.Cu" "B.Mask" "B.Paste")
			(net "GND")
		)
		(pad "135" smd rect
			(at 0 119.000016 270)
			(size 1.8034 0.508)
			(layers "B.Cu" "B.Mask" "B.Paste")
			(net "M_B_DQ<62>")
		)
		(pad "136" smd rect
			(at 0 119.8499 270)
			(size 1.8034 0.508)
			(layers "B.Cu" "B.Mask" "B.Paste")
			(net "GND")
		)
		(pad "137" smd rect
			(at 0 120.700038 270)
			(size 1.8034 0.508)
			(layers "B.Cu" "B.Mask" "B.Paste")
			(net "M_B_DQ<58>")
		)
		(pad "138" smd rect
			(at 0 121.549922 270)
			(size 1.8034 0.508)
			(layers "B.Cu" "B.Mask" "B.Paste")
			(net "GND")
		)
		(pad "139" smd rect
			(at 0 122.40006 270)
			(size 1.8034 0.508)
			(layers "B.Cu" "B.Mask" "B.Paste")
			(net "PVPP_ABC")
		)
		(pad "140" smd rect
			(at 0 123.249944 270)
			(size 1.8034 0.508)
			(layers "B.Cu" "B.Mask" "B.Paste")
			(net "PVPP_ABC")
		)
		(pad "141" smd rect
			(at 0 124.100082 270)
			(size 1.8034 0.508)
			(layers "B.Cu" "B.Mask" "B.Paste")
			(net "SMB_DDR_ABC_VPP_SCL")
		)
		(pad "142" smd rect
			(at 0 124.949966 270)
			(size 1.8034 0.508)
			(layers "B.Cu" "B.Mask" "B.Paste")
			(net "PVPP_ABC")
		)
		(pad "143" smd rect
			(at 0 125.800104 270)
			(size 1.8034 0.508)
			(layers "B.Cu" "B.Mask" "B.Paste")
			(net "PVPP_ABC")
		)
		(pad "144" smd rect
			(at 0 126.649988 270)
			(size 1.8034 0.508)
			(layers "B.Cu" "B.Mask" "B.Paste")
			(net "TP_CH_B_DIMM_B1_RFU_2")
		)
		(pad "145" smd rect
			(at -4.59994 0 270)
			(size 1.8034 0.508)
			(layers "B.Cu" "B.Mask" "B.Paste")
			(net "P12V_NVDIMM_ABC")
		)
		(pad "146" smd rect
			(at -4.59994 0.849884 270)
			(size 1.8034 0.508)
			(layers "B.Cu" "B.Mask" "B.Paste")
			(net "M_B_VREF")
		)
		(pad "147" smd rect
			(at -4.59994 1.700022 270)
			(size 1.8034 0.508)
			(layers "B.Cu" "B.Mask" "B.Paste")
			(net "GND")
		)
		(pad "148" smd rect
			(at -4.59994 2.549906 270)
			(size 1.8034 0.508)
			(layers "B.Cu" "B.Mask" "B.Paste")
			(net "M_B_DQ<5>")
		)
	)
)
